(kicad_pcb
	(version 20260206)
	(generator "pcbnew")
	(generator_version "10.0")
	(general
		(thickness 1.6)
		(legacy_teardrops no)
	)
	(paper "A4")
	(title_block
		(title "netronome-mezz — pcbd0082-001_rev01_jul9_a.brd")
		(comment 1 "Open CloudServer (Microsoft) / footprints 297-304 of 714")
	)
	(layers
		(0 "F.Cu" signal "TOP")
		(4 "In1.Cu" signal "02_GND")
		(6 "In2.Cu" signal "03_SIG")
		(8 "In3.Cu" signal "04_SIG")
		(10 "In4.Cu" signal "05_GND")
		(12 "In5.Cu" signal "06_PWR1")
		(14 "In6.Cu" signal "07_SIG")
		(16 "In7.Cu" signal "08_SIG")
		(18 "In8.Cu" signal "09_GND")
		(2 "B.Cu" signal "BOTTOM")
		(9 "F.Adhes" user "F.Adhesive")
		(11 "B.Adhes" user "B.Adhesive")
		(13 "F.Paste" user "Package Geometry/Pastemask Top")
		(15 "B.Paste" user "Package Geometry/Pastemask Bottom")
		(5 "F.SilkS" user "Ref Des/Silkscreen Top")
		(7 "B.SilkS" user "Ref Des/Silkscreen Bottom")
		(1 "F.Mask" user "Board Geometry/Soldermask Top")
		(3 "B.Mask" user "Board Geometry/Soldermask Bottom")
		(17 "Dwgs.User" user "User.Drawings")
		(19 "Cmts.User" user "User.Comments")
		(21 "Eco1.User" user "User.Eco1")
		(23 "Eco2.User" user "User.Eco2")
		(25 "Edge.Cuts" user "Board Geometry/Outline")
		(27 "Margin" user)
		(31 "F.CrtYd" user "Package Geometry/Place Bound Top")
		(29 "B.CrtYd" user "Package Geometry/Place Bound Bottom")
		(35 "F.Fab" user "Ref Des/Assembly Top")
		(33 "B.Fab" user "Ref Des/Assembly Bottom")
		(45 "User.4" user "COMPVAL_TYPE_BOTTOM")
	)
	(footprint ""
		(layer "F.Cu")
		(at 80.137 28.702 180)
		(property "Reference" "R216"
			(at 0 0 180)
			(layer "F.SilkS")
			(hide yes)
			(effects
				(font
					(size 1.27 1.27)
				)
			)
		)
		(property "Value" "39.0"
			(at -0.148158 1.3462 270)
			(unlocked yes)
			(layer "F.Fab")
			(hide yes)
			(effects
				(font
					(size 1.27 0.9652)
					(thickness 0.000001)
				)
				(justify left)
			)
		)
		(property "Device Type" "REST0108"
			(at -0.148158 1.3462 270)
			(unlocked yes)
			(layer "F.Fab")
			(hide yes)
			(effects
				(font
					(size 1.27 0.9652)
					(thickness 0.000001)
				)
				(justify left)
			)
		)
		(duplicate_pad_numbers_are_jumpers no)
		(fp_poly
			(pts
				(xy 0.635 1.0668) (xy 0.635 -1.0668) (xy -0.635 -1.0668) (xy -0.635 1.0668)
			)
			(stroke
				(width 0)
				(type default)
			)
			(fill no)
			(layer "F.CrtYd")
		)
		(fp_line
			(start 0.254 0.508)
			(end -0.254 0.508)
			(stroke
				(width 0.0254)
				(type default)
			)
			(layer "F.Fab")
		)
		(fp_line
			(start 0.254 -0.508)
			(end 0.254 0.508)
			(stroke
				(width 0.0254)
				(type default)
			)
			(layer "F.Fab")
		)
		(fp_line
			(start -0.254 0.508)
			(end -0.254 -0.508)
			(stroke
				(width 0.0254)
				(type default)
			)
			(layer "F.Fab")
		)
		(fp_line
			(start -0.254 -0.508)
			(end 0.254 -0.508)
			(stroke
				(width 0.0254)
				(type default)
			)
			(layer "F.Fab")
		)
		(pad "1" smd rect
			(at 0 -0.4191 180)
			(size 0.508 0.5334)
			(layers "F.Cu" "F.Mask" "F.Paste")
			(net "DDR0_32A_A10")
		)
		(pad "2" smd rect
			(at 0 0.4191 180)
			(size 0.508 0.5334)
			(layers "F.Cu" "F.Mask" "F.Paste")
			(net "DDR_VTT")
		)
		(zone
			(layer "F.Cu")
			(hatch none 0.5)
			(connect_pads
				(clearance 0)
			)
			(min_thickness 0.25)
			(keepout
				(tracks not_allowed)
				(vias allowed)
				(pads allowed)
				(copperpour not_allowed)
				(footprints allowed)
			)
			(placement
				(enabled no)
				(sheetname "")
			)
			(fill
				(thermal_gap 0.5)
				(thermal_bridge_width 0.5)
				(island_removal_mode 0)
			)
			(polygon
				(pts
					(xy 80.1116 28.7274) (xy 80.1116 28.6766) (xy 80.1624 28.6766) (xy 80.1624 28.7274)
				)
			)
		)
	)
	(footprint ""
		(layer "F.Cu")
		(at 45.974 51.816)
		(property "Reference" "C249"
			(at 0 0 0)
			(layer "F.SilkS")
			(hide yes)
			(effects
				(font
					(size 1.27 1.27)
				)
			)
		)
		(property "Value" "0.1UF"
			(at -0.091846 0.2921 90)
			(unlocked yes)
			(layer "F.Fab")
			(hide yes)
			(effects
				(font
					(size 0.7874 0.5842)
					(thickness 0.2032)
				)
				(justify left)
			)
		)
		(property "Device Type" "CAPC0073"
			(at -0.091846 0.2921 90)
			(unlocked yes)
			(layer "F.Fab")
			(hide yes)
			(effects
				(font
					(size 0.7874 0.5842)
					(thickness 0.2032)
				)
				(justify left)
			)
		)
		(duplicate_pad_numbers_are_jumpers no)
		(fp_poly
			(pts
				(xy 0.635 1.0668) (xy 0.635 -1.0668) (xy -0.635 -1.0668) (xy -0.635 1.0668)
			)
			(stroke
				(width 0)
				(type default)
			)
			(fill no)
			(layer "F.CrtYd")
		)
		(fp_line
			(start -0.254 -0.508)
			(end 0.254 -0.508)
			(stroke
				(width 0.0254)
				(type default)
			)
			(layer "F.Fab")
		)
		(fp_line
			(start -0.254 0.508)
			(end -0.254 -0.508)
			(stroke
				(width 0.0254)
				(type default)
			)
			(layer "F.Fab")
		)
		(fp_line
			(start 0.254 -0.508)
			(end 0.254 0.508)
			(stroke
				(width 0.0254)
				(type default)
			)
			(layer "F.Fab")
		)
		(fp_line
			(start 0.254 0.508)
			(end -0.254 0.508)
			(stroke
				(width 0.0254)
				(type default)
			)
			(layer "F.Fab")
		)
		(pad "1" smd rect
			(at 0 -0.4191)
			(size 0.508 0.5334)
			(layers "F.Cu" "F.Mask" "F.Paste")
			(net "EXT_3.3V_THRESHOLD")
		)
		(pad "2" smd rect
			(at 0 0.4191)
			(size 0.508 0.5334)
			(layers "F.Cu" "F.Mask" "F.Paste")
			(net "GND")
		)
		(zone
			(layer "F.Cu")
			(hatch none 0.5)
			(connect_pads
				(clearance 0)
			)
			(min_thickness 0.25)
			(keepout
				(tracks not_allowed)
				(vias allowed)
				(pads allowed)
				(copperpour not_allowed)
				(footprints allowed)
			)
			(placement
				(enabled no)
				(sheetname "")
			)
			(fill
				(thermal_gap 0.5)
				(thermal_bridge_width 0.5)
				(island_removal_mode 0)
			)
			(polygon
				(pts
					(xy 45.9994 51.7906) (xy 45.9994 51.8414) (xy 45.9486 51.8414) (xy 45.9486 51.7906)
				)
			)
		)
	)
	(footprint ""
		(layer "F.Cu")
		(at 75.946 5.715 -90)
		(property "Reference" "C214"
			(at -0.48133 4.318 0)
			(unlocked yes)
			(layer "F.SilkS")
			(effects
				(font
					(size 0.7874 0.5842)
					(thickness 0.127)
				)
				(justify left)
			)
		)
		(property "Value" "1UF"
			(at -0.091846 0.2921 0)
			(unlocked yes)
			(layer "F.Fab")
			(hide yes)
			(effects
				(font
					(size 0.7874 0.5842)
					(thickness 0.2032)
				)
				(justify left)
			)
		)
		(property "Device Type" "CAPC0028"
			(at -0.091846 0.2921 0)
			(unlocked yes)
			(layer "F.Fab")
			(hide yes)
			(effects
				(font
					(size 0.7874 0.5842)
					(thickness 0.2032)
				)
				(justify left)
			)
		)
		(duplicate_pad_numbers_are_jumpers no)
		(fp_poly
			(pts
				(xy 0.635 1.0668) (xy 0.635 -1.0668) (xy -0.635 -1.0668) (xy -0.635 1.0668)
			)
			(stroke
				(width 0)
				(type default)
			)
			(fill no)
			(layer "F.CrtYd")
		)
		(fp_line
			(start -0.254 0.508)
			(end -0.254 -0.508)
			(stroke
				(width 0.0254)
				(type default)
			)
			(layer "F.Fab")
		)
		(fp_line
			(start 0.254 0.508)
			(end -0.254 0.508)
			(stroke
				(width 0.0254)
				(type default)
			)
			(layer "F.Fab")
		)
		(fp_line
			(start -0.254 -0.508)
			(end 0.254 -0.508)
			(stroke
				(width 0.0254)
				(type default)
			)
			(layer "F.Fab")
		)
		(fp_line
			(start 0.254 -0.508)
			(end 0.254 0.508)
			(stroke
				(width 0.0254)
				(type default)
			)
			(layer "F.Fab")
		)
		(pad "1" smd rect
			(at 0 -0.4191 270)
			(size 0.508 0.5334)
			(layers "F.Cu" "F.Mask" "F.Paste")
			(net "DDR_VDDQ")
		)
		(pad "2" smd rect
			(at 0 0.4191 270)
			(size 0.508 0.5334)
			(layers "F.Cu" "F.Mask" "F.Paste")
			(net "GND")
		)
		(zone
			(layer "F.Cu")
			(hatch none 0.5)
			(connect_pads
				(clearance 0)
			)
			(min_thickness 0.25)
			(keepout
				(tracks not_allowed)
				(vias allowed)
				(pads allowed)
				(copperpour not_allowed)
				(footprints allowed)
			)
			(placement
				(enabled no)
				(sheetname "")
			)
			(fill
				(thermal_gap 0.5)
				(thermal_bridge_width 0.5)
				(island_removal_mode 0)
			)
			(polygon
				(pts
					(xy 75.9714 5.7404) (xy 75.9206 5.7404) (xy 75.9206 5.6896) (xy 75.9714 5.6896)
				)
			)
		)
	)
	(footprint ""
		(layer "F.Cu")
		(at 31.877 32.639 180)
		(property "Reference" "R90"
			(at 0 0 180)
			(layer "F.SilkS")
			(hide yes)
			(effects
				(font
					(size 1.27 1.27)
				)
			)
		)
		(property "Value" "4.75K"
			(at -0.148158 1.3462 270)
			(unlocked yes)
			(layer "F.Fab")
			(hide yes)
			(effects
				(font
					(size 1.27 0.9652)
					(thickness 0.000001)
				)
				(justify left)
			)
		)
		(property "Device Type" "REST4024"
			(at -0.148158 1.3462 270)
			(unlocked yes)
			(layer "F.Fab")
			(hide yes)
			(effects
				(font
					(size 1.27 0.9652)
					(thickness 0.000001)
				)
				(justify left)
			)
		)
		(duplicate_pad_numbers_are_jumpers no)
		(fp_poly
			(pts
				(xy 0.635 1.0668) (xy 0.635 -1.0668) (xy -0.635 -1.0668) (xy -0.635 1.0668)
			)
			(stroke
				(width 0)
				(type default)
			)
			(fill no)
			(layer "F.CrtYd")
		)
		(fp_line
			(start 0.254 0.508)
			(end -0.254 0.508)
			(stroke
				(width 0.0254)
				(type default)
			)
			(layer "F.Fab")
		)
		(fp_line
			(start 0.254 -0.508)
			(end 0.254 0.508)
			(stroke
				(width 0.0254)
				(type default)
			)
			(layer "F.Fab")
		)
		(fp_line
			(start -0.254 0.508)
			(end -0.254 -0.508)
			(stroke
				(width 0.0254)
				(type default)
			)
			(layer "F.Fab")
		)
		(fp_line
			(start -0.254 -0.508)
			(end 0.254 -0.508)
			(stroke
				(width 0.0254)
				(type default)
			)
			(layer "F.Fab")
		)
		(pad "1" smd rect
			(at 0 -0.4191 180)
			(size 0.508 0.5334)
			(layers "F.Cu" "F.Mask" "F.Paste")
			(net "_NFP_CORE_VID4")
		)
		(pad "2" smd rect
			(at 0 0.4191 180)
			(size 0.508 0.5334)
			(layers "F.Cu" "F.Mask" "F.Paste")
			(net "VDD_1.2V")
		)
		(zone
			(layer "F.Cu")
			(hatch none 0.5)
			(connect_pads
				(clearance 0)
			)
			(min_thickness 0.25)
			(keepout
				(tracks not_allowed)
				(vias allowed)
				(pads allowed)
				(copperpour not_allowed)
				(footprints allowed)
			)
			(placement
				(enabled no)
				(sheetname "")
			)
			(fill
				(thermal_gap 0.5)
				(thermal_bridge_width 0.5)
				(island_removal_mode 0)
			)
			(polygon
				(pts
					(xy 31.8516 32.6644) (xy 31.8516 32.6136) (xy 31.9024 32.6136) (xy 31.9024 32.6644)
				)
			)
		)
	)
	(footprint ""
		(layer "F.Cu")
		(at 80.391 47.752 -90)
		(property "Reference" "C51"
			(at 0 0 270)
			(layer "F.SilkS")
			(hide yes)
			(effects
				(font
					(size 1.27 1.27)
				)
			)
		)
		(property "Value" "1000PF"
			(at -0.091846 0.2921 0)
			(unlocked yes)
			(layer "F.Fab")
			(hide yes)
			(effects
				(font
					(size 0.7874 0.5842)
					(thickness 0.2032)
				)
				(justify left)
			)
		)
		(property "Device Type" "CAPC0083"
			(at -0.091846 0.2921 0)
			(unlocked yes)
			(layer "F.Fab")
			(hide yes)
			(effects
				(font
					(size 0.7874 0.5842)
					(thickness 0.2032)
				)
				(justify left)
			)
		)
		(duplicate_pad_numbers_are_jumpers no)
		(fp_poly
			(pts
				(xy 0.635 1.0668) (xy 0.635 -1.0668) (xy -0.635 -1.0668) (xy -0.635 1.0668)
			)
			(stroke
				(width 0)
				(type default)
			)
			(fill no)
			(layer "F.CrtYd")
		)
		(fp_line
			(start -0.254 0.508)
			(end -0.254 -0.508)
			(stroke
				(width 0.0254)
				(type default)
			)
			(layer "F.Fab")
		)
		(fp_line
			(start 0.254 0.508)
			(end -0.254 0.508)
			(stroke
				(width 0.0254)
				(type default)
			)
			(layer "F.Fab")
		)
		(fp_line
			(start -0.254 -0.508)
			(end 0.254 -0.508)
			(stroke
				(width 0.0254)
				(type default)
			)
			(layer "F.Fab")
		)
		(fp_line
			(start 0.254 -0.508)
			(end 0.254 0.508)
			(stroke
				(width 0.0254)
				(type default)
			)
			(layer "F.Fab")
		)
		(pad "1" smd rect
			(at 0 -0.4191 270)
			(size 0.508 0.5334)
			(layers "F.Cu" "F.Mask" "F.Paste")
			(net "11N2258")
		)
		(pad "2" smd rect
			(at 0 0.4191 270)
			(size 0.508 0.5334)
			(layers "F.Cu" "F.Mask" "F.Paste")
			(net "GND")
		)
		(zone
			(layer "F.Cu")
			(hatch none 0.5)
			(connect_pads
				(clearance 0)
			)
			(min_thickness 0.25)
			(keepout
				(tracks not_allowed)
				(vias allowed)
				(pads allowed)
				(copperpour not_allowed)
				(footprints allowed)
			)
			(placement
				(enabled no)
				(sheetname "")
			)
			(fill
				(thermal_gap 0.5)
				(thermal_bridge_width 0.5)
				(island_removal_mode 0)
			)
			(polygon
				(pts
					(xy 80.4164 47.7774) (xy 80.3656 47.7774) (xy 80.3656 47.7266) (xy 80.4164 47.7266)
				)
			)
		)
	)
	(footprint ""
		(layer "F.Cu")
		(at 48.2346 53.594 90)
		(property "Reference" "C182"
			(at -1.143 1.93167 90)
			(unlocked yes)
			(layer "F.SilkS")
			(effects
				(font
					(size 0.7874 0.5842)
					(thickness 0.127)
				)
				(justify left)
			)
		)
		(property "Value" ""
			(at 0 0 90)
			(layer "F.Fab")
			(effects
				(font
					(size 1.27 1.27)
				)
			)
		)
		(duplicate_pad_numbers_are_jumpers no)
		(fp_arc
			(start 0.206578 -0.464261)
			(mid 0.300675 -0.409652)
			(end 0.381 -0.336271)
			(stroke
				(width 0.2032)
				(type default)
			)
			(layer "F.SilkS")
		)
		(fp_arc
			(start 0.381 0.336017)
			(mid 0.367833 0.350371)
			(end 0.354127 0.364211)
			(stroke
				(width 0.2032)
				(type default)
			)
			(layer "F.SilkS")
		)
		(fp_circle
			(center 0 0)
			(end 0 0.508)
			(stroke
				(width 0.2032)
				(type default)
			)
			(fill no)
			(layer "F.SilkS")
		)
		(fp_poly
			(pts
				(xy -1.905 1.778) (xy -1.905 -1.778) (xy 2.286 -1.778) (xy 2.286 1.778)
			)
			(stroke
				(width 0)
				(type default)
			)
			(fill no)
			(layer "F.CrtYd")
		)
		(fp_line
			(start 1.524 -1.27)
			(end 1.524 1.27)
			(stroke
				(width 0.0254)
				(type default)
			)
			(layer "F.Fab")
		)
		(fp_line
			(start -1.524 -1.27)
			(end 1.524 -1.27)
			(stroke
				(width 0.0254)
				(type default)
			)
			(layer "F.Fab")
		)
		(fp_line
			(start 1.524 1.27)
			(end -1.524 1.27)
			(stroke
				(width 0.0254)
				(type default)
			)
			(layer "F.Fab")
		)
		(fp_line
			(start -1.524 1.27)
			(end -1.524 -1.27)
			(stroke
				(width 0.0254)
				(type default)
			)
			(layer "F.Fab")
		)
		(pad "1" smd rect
			(at -1.4224 0 180)
			(size 2.7432 1.3716)
			(layers "F.Cu" "F.Mask" "F.Paste")
			(net "VDD_5.0V")
		)
		(pad "2" smd rect
			(at 1.4224 0 180)
			(size 2.7432 1.3716)
			(layers "F.Cu" "F.Mask" "F.Paste")
			(net "GND")
		)
	)
	(footprint ""
		(layer "F.Cu")
		(at 81.407 22.479 -90)
		(property "Reference" "C108"
			(at 0 0 270)
			(layer "F.SilkS")
			(hide yes)
			(effects
				(font
					(size 1.27 1.27)
				)
			)
		)
		(property "Value" "0.1UF"
			(at -0.091846 0.2921 0)
			(unlocked yes)
			(layer "F.Fab")
			(hide yes)
			(effects
				(font
					(size 0.7874 0.5842)
					(thickness 0.2032)
				)
				(justify left)
			)
		)
		(property "Device Type" "CAPC0073"
			(at -0.091846 0.2921 0)
			(unlocked yes)
			(layer "F.Fab")
			(hide yes)
			(effects
				(font
					(size 0.7874 0.5842)
					(thickness 0.2032)
				)
				(justify left)
			)
		)
		(duplicate_pad_numbers_are_jumpers no)
		(fp_poly
			(pts
				(xy 0.635 1.0668) (xy 0.635 -1.0668) (xy -0.635 -1.0668) (xy -0.635 1.0668)
			)
			(stroke
				(width 0)
				(type default)
			)
			(fill no)
			(layer "F.CrtYd")
		)
		(fp_line
			(start -0.254 0.508)
			(end -0.254 -0.508)
			(stroke
				(width 0.0254)
				(type default)
			)
			(layer "F.Fab")
		)
		(fp_line
			(start 0.254 0.508)
			(end -0.254 0.508)
			(stroke
				(width 0.0254)
				(type default)
			)
			(layer "F.Fab")
		)
		(fp_line
			(start -0.254 -0.508)
			(end 0.254 -0.508)
			(stroke
				(width 0.0254)
				(type default)
			)
			(layer "F.Fab")
		)
		(fp_line
			(start 0.254 -0.508)
			(end 0.254 0.508)
			(stroke
				(width 0.0254)
				(type default)
			)
			(layer "F.Fab")
		)
		(pad "1" smd rect
			(at 0 -0.4191 270)
			(size 0.508 0.5334)
			(layers "F.Cu" "F.Mask" "F.Paste")
			(net "DDR_VDDQ")
		)
		(pad "2" smd rect
			(at 0 0.4191 270)
			(size 0.508 0.5334)
			(layers "F.Cu" "F.Mask" "F.Paste")
			(net "DDR_VTT")
		)
		(zone
			(layer "F.Cu")
			(hatch none 0.5)
			(connect_pads
				(clearance 0)
			)
			(min_thickness 0.25)
			(keepout
				(tracks not_allowed)
				(vias allowed)
				(pads allowed)
				(copperpour not_allowed)
				(footprints allowed)
			)
			(placement
				(enabled no)
				(sheetname "")
			)
			(fill
				(thermal_gap 0.5)
				(thermal_bridge_width 0.5)
				(island_removal_mode 0)
			)
			(polygon
				(pts
					(xy 81.4324 22.5044) (xy 81.3816 22.5044) (xy 81.3816 22.4536) (xy 81.4324 22.4536)
				)
			)
		)
	)
	(footprint ""
		(layer "F.Cu")
		(at 34.544 32.639 180)
		(property "Reference" "R78"
			(at 0 0 180)
			(layer "F.SilkS")
			(hide yes)
			(effects
				(font
					(size 1.27 1.27)
				)
			)
		)
		(property "Value" "4.75K"
			(at -0.148158 1.3462 270)
			(unlocked yes)
			(layer "F.Fab")
			(hide yes)
			(effects
				(font
					(size 1.27 0.9652)
					(thickness 0.000001)
				)
				(justify left)
			)
		)
		(property "Device Type" "REST4024"
			(at -0.148158 1.3462 270)
			(unlocked yes)
			(layer "F.Fab")
			(hide yes)
			(effects
				(font
					(size 1.27 0.9652)
					(thickness 0.000001)
				)
				(justify left)
			)
		)
		(duplicate_pad_numbers_are_jumpers no)
		(fp_poly
			(pts
				(xy 0.635 1.0668) (xy 0.635 -1.0668) (xy -0.635 -1.0668) (xy -0.635 1.0668)
			)
			(stroke
				(width 0)
				(type default)
			)
			(fill no)
			(layer "F.CrtYd")
		)
		(fp_line
			(start 0.254 0.508)
			(end -0.254 0.508)
			(stroke
				(width 0.0254)
				(type default)
			)
			(layer "F.Fab")
		)
		(fp_line
			(start 0.254 -0.508)
			(end 0.254 0.508)
			(stroke
				(width 0.0254)
				(type default)
			)
			(layer "F.Fab")
		)
		(fp_line
			(start -0.254 0.508)
			(end -0.254 -0.508)
			(stroke
				(width 0.0254)
				(type default)
			)
			(layer "F.Fab")
		)
		(fp_line
			(start -0.254 -0.508)
			(end 0.254 -0.508)
			(stroke
				(width 0.0254)
				(type default)
			)
			(layer "F.Fab")
		)
		(pad "1" smd rect
			(at 0 -0.4191 180)
			(size 0.508 0.5334)
			(layers "F.Cu" "F.Mask" "F.Paste")
			(net "_NFP_CORE_VID6")
		)
		(pad "2" smd rect
			(at 0 0.4191 180)
			(size 0.508 0.5334)
			(layers "F.Cu" "F.Mask" "F.Paste")
			(net "VDD_1.2V")
		)
		(zone
			(layer "F.Cu")
			(hatch none 0.5)
			(connect_pads
				(clearance 0)
			)
			(min_thickness 0.25)
			(keepout
				(tracks not_allowed)
				(vias allowed)
				(pads allowed)
				(copperpour not_allowed)
				(footprints allowed)
			)
			(placement
				(enabled no)
				(sheetname "")
			)
			(fill
				(thermal_gap 0.5)
				(thermal_bridge_width 0.5)
				(island_removal_mode 0)
			)
			(polygon
				(pts
					(xy 34.5186 32.6644) (xy 34.5186 32.6136) (xy 34.5694 32.6136) (xy 34.5694 32.6644)
				)
			)
		)
	)
)
